# T6G (Grand Teton) — schematic netlist excerpt (pin names and nets, part order shuffled) for the footprints in the layout excerpt that follows; sources: Cadence DE-HDL packaged netlist, KiCad conversion of 04192023_DAF0TMB3IC0_F0TG_MB_C_brd_V02_OCP.brd

R3100  Q_RES  130 1% CHIP  pkg 0402LF  page 254 : A = LED_P3V3 ; B = P3V3
R3210  Q_RES  22 1% EMPTY  pkg 0402LF  page 138 : A = NCSI_BMC_CRS_DV_R1 ; B = RMII_OCP_BMC_CRSDV

(kicad_pcb
	(version 20260206)
	(generator "pcbnew")
	(generator_version "10.0")
	(general
		(thickness 1.6)
		(legacy_teardrops no)
	)
	(paper "A4")
	(title_block
		(title "04192023_DAF0TMB3IC0_F0TG_MB_C_brd_V02_OCP.brd")
		(comment 1 "Grand Teton / footprints 8042-8043 of 8354")
	)
	(layers
		(0 "F.Cu" signal "TOP")
		(4 "In1.Cu" signal "GND")
		(6 "In2.Cu" signal "IN1")
		(8 "In3.Cu" signal "GND1")
		(10 "In4.Cu" signal "IN2")
		(12 "In5.Cu" signal "GND2")
		(14 "In6.Cu" signal "IN3")
		(16 "In7.Cu" signal "GND3")
		(18 "In8.Cu" signal "VCC")
		(20 "In9.Cu" signal "VCC1")
		(22 "In10.Cu" signal "GND4")
		(24 "In11.Cu" signal "IN4")
		(26 "In12.Cu" signal "GND5")
		(28 "In13.Cu" signal "IN5")
		(30 "In14.Cu" signal "GND6")
		(32 "In15.Cu" signal "IN6")
		(34 "In16.Cu" signal "GND7")
		(2 "B.Cu" signal "BOTTOM")
		(9 "F.Adhes" user "F.Adhesive")
		(11 "B.Adhes" user "B.Adhesive")
		(13 "F.Paste" user "Package Geometry/Pastemask Top")
		(15 "B.Paste" user "Package Geometry/Pastemask Bottom")
		(5 "F.SilkS" user "Ref Des/Silkscreen Top")
		(7 "B.SilkS" user "Ref Des/Silkscreen Bottom")
		(1 "F.Mask" user "Board Geometry/Soldermask Top")
		(3 "B.Mask" user "Board Geometry/Soldermask Bottom")
		(17 "Dwgs.User" user "User.Drawings")
		(19 "Cmts.User" user "User.Comments")
		(21 "Eco1.User" user "User.Eco1")
		(23 "Eco2.User" user "User.Eco2")
		(25 "Edge.Cuts" user "Board Geometry/Outline")
		(27 "Margin" user)
		(31 "F.CrtYd" user "Package Geometry/Place Bound Top")
		(29 "B.CrtYd" user "Package Geometry/Place Bound Bottom")
		(35 "F.Fab" user "Ref Des/Assembly Top")
		(33 "B.Fab" user "Ref Des/Assembly Bottom")
	)
	(footprint ""
		(layer "B.Cu")
		(at 203.073 -75.053952)
		(property "Reference" "R3210"
			(at 0 0 0)
			(layer "B.SilkS")
			(hide yes)
			(effects
				(font
					(size 1.27 1.27)
				)
				(justify mirror)
			)
		)
		(property "Value" ""
			(at 0 0 0)
			(layer "B.Fab")
			(effects
				(font
					(size 1.27 1.27)
				)
				(justify mirror)
			)
		)
		(duplicate_pad_numbers_are_jumpers no)
		(fp_line
			(start -0.7874 -0.4064)
			(end -0.7874 0.4064)
			(stroke
				(width 0.1524)
				(type default)
			)
			(layer "B.SilkS")
		)
		(fp_line
			(start -0.7874 0.4064)
			(end 0.7874 0.4064)
			(stroke
				(width 0.1524)
				(type default)
			)
			(layer "B.SilkS")
		)
		(fp_line
			(start 0.7874 -0.4064)
			(end -0.7874 -0.4064)
			(stroke
				(width 0.1524)
				(type default)
			)
			(layer "B.SilkS")
		)
		(fp_line
			(start 0.7874 0.4064)
			(end 0.7874 -0.4064)
			(stroke
				(width 0.1524)
				(type default)
			)
			(layer "B.SilkS")
		)
		(fp_line
			(start -0.67945 -0.3048)
			(end -0.67945 0.3048)
			(stroke
				(width 0.1)
				(type default)
			)
			(layer "B.Fab")
		)
		(fp_line
			(start -0.67945 0.3048)
			(end -0.120396 0.3048)
			(stroke
				(width 0.1)
				(type default)
			)
			(layer "B.Fab")
		)
		(fp_line
			(start -0.12065 -0.3048)
			(end -0.67945 -0.3048)
			(stroke
				(width 0.1)
				(type default)
			)
			(layer "B.Fab")
		)
		(fp_line
			(start -0.12065 -0.2794)
			(end -0.12065 -0.3048)
			(stroke
				(width 0.1)
				(type default)
			)
			(layer "B.Fab")
		)
		(fp_line
			(start -0.120396 0.2794)
			(end 0.12065 0.2794)
			(stroke
				(width 0.1)
				(type default)
			)
			(layer "B.Fab")
		)
		(fp_line
			(start -0.120396 0.3048)
			(end -0.120396 0.2794)
			(stroke
				(width 0.1)
				(type default)
			)
			(layer "B.Fab")
		)
		(fp_line
			(start 0.12065 -0.305054)
			(end 0.12065 -0.2794)
			(stroke
				(width 0.1)
				(type default)
			)
			(layer "B.Fab")
		)
		(fp_line
			(start 0.12065 -0.2794)
			(end -0.12065 -0.2794)
			(stroke
				(width 0.1)
				(type default)
			)
			(layer "B.Fab")
		)
		(fp_line
			(start 0.12065 0.2794)
			(end 0.12065 0.3048)
			(stroke
				(width 0.1)
				(type default)
			)
			(layer "B.Fab")
		)
		(fp_line
			(start 0.12065 0.3048)
			(end 0.67945 0.3048)
			(stroke
				(width 0.1)
				(type default)
			)
			(layer "B.Fab")
		)
		(fp_line
			(start 0.67945 -0.305054)
			(end 0.12065 -0.305054)
			(stroke
				(width 0.1)
				(type default)
			)
			(layer "B.Fab")
		)
		(fp_line
			(start 0.67945 0.3048)
			(end 0.67945 -0.305054)
			(stroke
				(width 0.1)
				(type default)
			)
			(layer "B.Fab")
		)
		(pad "1" smd circle
			(at 0.40005 0 180)
			(size 0 0)
			(layers "B.Cu" "B.Mask" "B.Paste")
			(net "NCSI_BMC_CRS_DV_R1")
		)
		(pad "2" smd circle
			(at -0.40005 0 180)
			(size 0 0)
			(layers "B.Cu" "B.Mask" "B.Paste")
			(net "RMII_OCP_BMC_CRSDV")
		)
	)
	(footprint ""
		(layer "B.Cu")
		(at 316.507876 -66.708782 90)
		(property "Reference" "R3100"
			(at 0 0 90)
			(layer "B.SilkS")
			(hide yes)
			(effects
				(font
					(size 1.27 1.27)
				)
				(justify mirror)
			)
		)
		(property "Value" ""
			(at 0 0 90)
			(layer "B.Fab")
			(effects
				(font
					(size 1.27 1.27)
				)
				(justify mirror)
			)
		)
		(duplicate_pad_numbers_are_jumpers no)
		(fp_line
			(start 0.7874 -0.4064)
			(end -0.7874 -0.4064)
			(stroke
				(width 0.1524)
				(type default)
			)
			(layer "B.SilkS")
		)
		(fp_line
			(start -0.7874 -0.4064)
			(end -0.7874 0.4064)
			(stroke
				(width 0.1524)
				(type default)
			)
			(layer "B.SilkS")
		)
		(fp_line
			(start 0.7874 0.4064)
			(end 0.7874 -0.4064)
			(stroke
				(width 0.1524)
				(type default)
			)
			(layer "B.SilkS")
		)
		(fp_line
			(start -0.7874 0.4064)
			(end 0.7874 0.4064)
			(stroke
				(width 0.1524)
				(type default)
			)
			(layer "B.SilkS")
		)
		(fp_line
			(start 0.67945 -0.305054)
			(end 0.12065 -0.305054)
			(stroke
				(width 0.1)
				(type default)
			)
			(layer "B.Fab")
		)
		(fp_line
			(start 0.12065 -0.305054)
			(end 0.12065 -0.2794)
			(stroke
				(width 0.1)
				(type default)
			)
			(layer "B.Fab")
		)
		(fp_line
			(start -0.12065 -0.3048)
			(end -0.67945 -0.3048)
			(stroke
				(width 0.1)
				(type default)
			)
			(layer "B.Fab")
		)
		(fp_line
			(start -0.67945 -0.3048)
			(end -0.67945 0.3048)
			(stroke
				(width 0.1)
				(type default)
			)
			(layer "B.Fab")
		)
		(fp_line
			(start 0.12065 -0.2794)
			(end -0.12065 -0.2794)
			(stroke
				(width 0.1)
				(type default)
			)
			(layer "B.Fab")
		)
		(fp_line
			(start -0.12065 -0.2794)
			(end -0.12065 -0.3048)
			(stroke
				(width 0.1)
				(type default)
			)
			(layer "B.Fab")
		)
		(fp_line
			(start 0.12065 0.2794)
			(end 0.12065 0.3048)
			(stroke
				(width 0.1)
				(type default)
			)
			(layer "B.Fab")
		)
		(fp_line
			(start -0.120396 0.2794)
			(end 0.12065 0.2794)
			(stroke
				(width 0.1)
				(type default)
			)
			(layer "B.Fab")
		)
		(fp_line
			(start 0.67945 0.3048)
			(end 0.67945 -0.305054)
			(stroke
				(width 0.1)
				(type default)
			)
			(layer "B.Fab")
		)
		(fp_line
			(start 0.12065 0.3048)
			(end 0.67945 0.3048)
			(stroke
				(width 0.1)
				(type default)
			)
			(layer "B.Fab")
		)
		(fp_line
			(start -0.120396 0.3048)
			(end -0.120396 0.2794)
			(stroke
				(width 0.1)
				(type default)
			)
			(layer "B.Fab")
		)
		(fp_line
			(start -0.67945 0.3048)
			(end -0.120396 0.3048)
			(stroke
				(width 0.1)
				(type default)
			)
			(layer "B.Fab")
		)
		(pad "1" smd circle
			(at 0.40005 0 270)
			(size 0 0)
			(layers "B.Cu" "B.Mask" "B.Paste")
			(net "LED_P3V3")
		)
		(pad "2" smd circle
			(at -0.40005 0 270)
			(size 0 0)
			(layers "B.Cu" "B.Mask" "B.Paste")
			(net "P3V3")
		)
	)
)
